(kicad_pcb
	(version 20260206)
	(generator "pcbnew")
	(generator_version "10.0")
	(general
		(thickness 1.6)
		(legacy_teardrops no)
	)
	(paper "A4")
	(title_block
		(title "01162023_DA0F0TEBIF0_F0T_Expander_BD_F_brd_V02_OCP.brd")
		(comment 1 "Grand Teton / footprints 1802-1806 of 9728")
	)
	(layers
		(0 "F.Cu" signal "TOP")
		(4 "In1.Cu" signal "GND")
		(6 "In2.Cu" signal "VCC")
		(8 "In3.Cu" signal "VCC1")
		(10 "In4.Cu" signal "GND1")
		(12 "In5.Cu" signal "IN1")
		(14 "In6.Cu" signal "GND2")
		(16 "In7.Cu" signal "IN2")
		(18 "In8.Cu" signal "GND3")
		(20 "In9.Cu" signal "IN3")
		(22 "In10.Cu" signal "GND4")
		(24 "In11.Cu" signal "IN4")
		(26 "In12.Cu" signal "GND5")
		(28 "In13.Cu" signal "IN5")
		(30 "In14.Cu" signal "GND6")
		(32 "In15.Cu" signal "IN6")
		(34 "In16.Cu" signal "GND7")
		(2 "B.Cu" signal "BOTTOM")
		(9 "F.Adhes" user "F.Adhesive")
		(11 "B.Adhes" user "B.Adhesive")
		(13 "F.Paste" user "Package Geometry/Pastemask Top")
		(15 "B.Paste" user "Package Geometry/Pastemask Bottom")
		(5 "F.SilkS" user "Ref Des/Silkscreen Top")
		(7 "B.SilkS" user "Ref Des/Silkscreen Bottom")
		(1 "F.Mask" user "Board Geometry/Soldermask Top")
		(3 "B.Mask" user "Board Geometry/Soldermask Bottom")
		(17 "Dwgs.User" user "User.Drawings")
		(19 "Cmts.User" user "User.Comments")
		(21 "Eco1.User" user "User.Eco1")
		(23 "Eco2.User" user "User.Eco2")
		(25 "Edge.Cuts" user "Board Geometry/Outline")
		(27 "Margin" user)
		(31 "F.CrtYd" user "Package Geometry/Place Bound Top")
		(29 "B.CrtYd" user "Package Geometry/Place Bound Bottom")
		(35 "F.Fab" user "Ref Des/Assembly Top")
		(33 "B.Fab" user "Ref Des/Assembly Bottom")
	)
	(footprint ""
		(layer "F.Cu")
		(at 271.899888 -378.70003)
		(property "Reference" "H78"
			(at 7.60222 -4.224782 0)
			(unlocked yes)
			(layer "F.SilkS")
			(effects
				(font
					(size 0.7874 0.5842)
					(thickness 0.1524)
				)
				(justify left)
			)
		)
		(property "Value" ""
			(at 0 0 0)
			(layer "F.Fab")
			(effects
				(font
					(size 1.27 1.27)
				)
			)
		)
		(duplicate_pad_numbers_are_jumpers no)
		(fp_arc
			(start 1.57988 -7.842504)
			(mid 6.190226 -5.067585)
			(end 7.999984 0)
			(stroke
				(width 0.1524)
				(type default)
			)
			(layer "F.SilkS")
		)
		(fp_arc
			(start 7.999984 0)
			(mid -3.377445 7.252026)
			(end -5.148072 -6.123432)
			(stroke
				(width 0.1524)
				(type default)
			)
			(layer "F.SilkS")
		)
		(fp_arc
			(start 1.711198 -7.814818)
			(mid 6.232558 -5.015484)
			(end 7.999984 0)
			(stroke
				(width 0.1524)
				(type default)
			)
			(layer "B.SilkS")
		)
		(fp_arc
			(start 7.999984 0)
			(mid -3.325733 7.27586)
			(end -5.234686 -6.049518)
			(stroke
				(width 0.1524)
				(type default)
			)
			(layer "B.SilkS")
		)
		(fp_circle
			(center 0 0)
			(end 7.999984 0)
			(stroke
				(width 0.1)
				(type default)
			)
			(fill no)
			(layer "B.Fab")
		)
		(fp_circle
			(center 0 0)
			(end 7.999984 0)
			(stroke
				(width 0.1)
				(type default)
			)
			(fill no)
			(layer "F.Fab")
		)
		(pad "" np_thru_hole circle
			(at 0 0)
			(size 3.4036 3.4036)
			(drill 3.4036)
			(layers "*.Cu" "*.Mask")
			(clearance 0.381)
			(thermal_gap 0.381)
		)
		(pad "2" thru_hole circle
			(at 3.606292 0)
			(size 0.762 0.762)
			(drill 0.5588)
			(layers "*.Cu" "*.Mask")
			(remove_unused_layers no)
			(net "GND")
			(clearance 0.1524)
			(thermal_gap 0.1524)
		)
		(pad "3" thru_hole circle
			(at 2.549906 -2.549906)
			(size 0.762 0.762)
			(drill 0.5588)
			(layers "*.Cu" "*.Mask")
			(remove_unused_layers no)
			(net "GND")
			(clearance 0.1524)
			(thermal_gap 0.1524)
		)
		(pad "4" thru_hole circle
			(at 0 -3.606292)
			(size 0.762 0.762)
			(drill 0.5588)
			(layers "*.Cu" "*.Mask")
			(remove_unused_layers no)
			(net "GND")
			(clearance 0.1524)
			(thermal_gap 0.1524)
		)
		(pad "5" thru_hole circle
			(at -2.549906 -2.549906)
			(size 0.762 0.762)
			(drill 0.5588)
			(layers "*.Cu" "*.Mask")
			(remove_unused_layers no)
			(net "GND")
			(clearance 0.1524)
			(thermal_gap 0.1524)
		)
		(pad "6" thru_hole circle
			(at -3.606292 0)
			(size 0.762 0.762)
			(drill 0.5588)
			(layers "*.Cu" "*.Mask")
			(remove_unused_layers no)
			(net "GND")
			(clearance 0.1524)
			(thermal_gap 0.1524)
		)
		(pad "7" thru_hole circle
			(at -2.549906 2.549906)
			(size 0.762 0.762)
			(drill 0.5588)
			(layers "*.Cu" "*.Mask")
			(remove_unused_layers no)
			(net "GND")
			(clearance 0.1524)
			(thermal_gap 0.1524)
		)
		(pad "8" thru_hole circle
			(at 0 3.606292)
			(size 0.762 0.762)
			(drill 0.5588)
			(layers "*.Cu" "*.Mask")
			(remove_unused_layers no)
			(net "GND")
			(clearance 0.1524)
			(thermal_gap 0.1524)
		)
		(pad "9" thru_hole circle
			(at 2.549906 2.549906)
			(size 0.762 0.762)
			(drill 0.5588)
			(layers "*.Cu" "*.Mask")
			(remove_unused_layers no)
			(net "GND")
			(clearance 0.1524)
			(thermal_gap 0.1524)
		)
		(zone
			(layer "F.Cu")
			(hatch none 0.5)
			(connect_pads
				(clearance 0)
			)
			(min_thickness 0.25)
			(keepout
				(tracks not_allowed)
				(vias allowed)
				(pads allowed)
				(copperpour not_allowed)
				(footprints allowed)
			)
			(placement
				(enabled no)
				(sheetname "")
			)
			(fill
				(thermal_gap 0.5)
				(thermal_bridge_width 0.5)
				(island_removal_mode 0)
			)
			(polygon
				(pts
					(arc
						(start 271.899888 -370.700046)
						(mid 263.899904 -378.70003)
						(end 271.899888 -386.700014)
					)
					(arc
						(start 271.899888 -383.95402)
						(mid 266.645898 -378.70003)
						(end 271.899888 -373.44604)
					)
				)
			)
		)
		(zone
			(layer "F.Cu")
			(hatch none 0.5)
			(connect_pads
				(clearance 0)
			)
			(min_thickness 0.25)
			(keepout
				(tracks not_allowed)
				(vias allowed)
				(pads allowed)
				(copperpour not_allowed)
				(footprints allowed)
			)
			(placement
				(enabled no)
				(sheetname "")
			)
			(fill
				(thermal_gap 0.5)
				(thermal_bridge_width 0.5)
				(island_removal_mode 0)
			)
			(polygon
				(pts
					(arc
						(start 271.899888 -370.700046)
						(mid 279.899872 -378.70003)
						(end 271.899888 -386.700014)
					)
					(arc
						(start 271.899888 -383.95402)
						(mid 277.153878 -378.70003)
						(end 271.899888 -373.44604)
					)
				)
			)
		)
		(zone
			(layers "F.Cu" "B.Cu" "In1.Cu" "In2.Cu" "In3.Cu" "In4.Cu" "In5.Cu" "In6.Cu"
				"In7.Cu" "In8.Cu" "In9.Cu" "In10.Cu" "In11.Cu" "In12.Cu" "In13.Cu" "In14.Cu"
				"In15.Cu" "In16.Cu"
			)
			(hatch none 0.5)
			(connect_pads
				(clearance 0)
			)
			(min_thickness 0.25)
			(keepout
				(tracks not_allowed)
				(vias allowed)
				(pads allowed)
				(copperpour not_allowed)
				(footprints allowed)
			)
			(placement
				(enabled no)
				(sheetname "")
			)
			(fill
				(thermal_gap 0.5)
				(thermal_bridge_width 0.5)
				(island_removal_mode 0)
			)
			(polygon
				(pts
					(arc
						(start 274.109688 -378.70003)
						(mid 269.690088 -378.70003)
						(end 274.109688 -378.70003)
					)
				)
			)
		)
		(zone
			(layer "B.Cu")
			(hatch none 0.5)
			(connect_pads
				(clearance 0)
			)
			(min_thickness 0.25)
			(keepout
				(tracks not_allowed)
				(vias allowed)
				(pads allowed)
				(copperpour not_allowed)
				(footprints allowed)
			)
			(placement
				(enabled no)
				(sheetname "")
			)
			(fill
				(thermal_gap 0.5)
				(thermal_bridge_width 0.5)
				(island_removal_mode 0)
			)
			(polygon
				(pts
					(arc
						(start 271.899888 -373.19204)
						(mid 266.391898 -378.70003)
						(end 271.899888 -384.20802)
					)
					(arc
						(start 271.899888 -383.72542)
						(mid 266.874498 -378.70003)
						(end 271.899888 -373.67464)
					)
				)
			)
		)
		(zone
			(layer "B.Cu")
			(hatch none 0.5)
			(connect_pads
				(clearance 0)
			)
			(min_thickness 0.25)
			(keepout
				(tracks not_allowed)
				(vias allowed)
				(pads allowed)
				(copperpour not_allowed)
				(footprints allowed)
			)
			(placement
				(enabled no)
				(sheetname "")
			)
			(fill
				(thermal_gap 0.5)
				(thermal_bridge_width 0.5)
				(island_removal_mode 0)
			)
			(polygon
				(pts
					(arc
						(start 271.899888 -373.19204)
						(mid 277.407878 -378.70003)
						(end 271.899888 -384.20802)
					)
					(arc
						(start 271.899888 -383.72542)
						(mid 276.925278 -378.70003)
						(end 271.899888 -373.67464)
					)
				)
			)
		)
	)
	(footprint ""
		(layer "F.Cu")
		(at 30.081982 -289.790632 180)
		(property "Reference" "C3049"
			(at 0 0 180)
			(layer "F.SilkS")
			(hide yes)
			(effects
				(font
					(size 1.27 1.27)
				)
			)
		)
		(property "Value" ""
			(at 0 0 180)
			(layer "F.Fab")
			(effects
				(font
					(size 1.27 1.27)
				)
			)
		)
		(duplicate_pad_numbers_are_jumpers no)
		(fp_line
			(start 1.2954 0.5842)
			(end -1.2954 0.5842)
			(stroke
				(width 0.1524)
				(type default)
			)
			(layer "F.SilkS")
		)
		(fp_line
			(start 1.2954 -0.5842)
			(end 1.2954 0.5842)
			(stroke
				(width 0.1524)
				(type default)
			)
			(layer "F.SilkS")
		)
		(fp_line
			(start -1.2954 0.5842)
			(end -1.2954 -0.5842)
			(stroke
				(width 0.1524)
				(type default)
			)
			(layer "F.SilkS")
		)
		(fp_line
			(start -1.2954 -0.5842)
			(end 1.2954 -0.5842)
			(stroke
				(width 0.1524)
				(type default)
			)
			(layer "F.SilkS")
		)
		(fp_line
			(start 1.1938 0.4064)
			(end 0.8636 0.4064)
			(stroke
				(width 0.1)
				(type default)
			)
			(layer "F.Fab")
		)
		(fp_line
			(start 1.1938 -0.4064)
			(end 1.1938 0.4064)
			(stroke
				(width 0.1)
				(type default)
			)
			(layer "F.Fab")
		)
		(fp_line
			(start 0.8636 0.4572)
			(end -0.8636 0.4572)
			(stroke
				(width 0.1)
				(type default)
			)
			(layer "F.Fab")
		)
		(fp_line
			(start 0.8636 0.4064)
			(end 0.8636 0.4572)
			(stroke
				(width 0.1)
				(type default)
			)
			(layer "F.Fab")
		)
		(fp_line
			(start 0.8636 -0.4064)
			(end 1.1938 -0.4064)
			(stroke
				(width 0.1)
				(type default)
			)
			(layer "F.Fab")
		)
		(fp_line
			(start 0.8636 -0.4572)
			(end 0.8636 -0.4064)
			(stroke
				(width 0.1)
				(type default)
			)
			(layer "F.Fab")
		)
		(fp_line
			(start -0.8636 0.4572)
			(end -0.8636 0.4064)
			(stroke
				(width 0.1)
				(type default)
			)
			(layer "F.Fab")
		)
		(fp_line
			(start -0.8636 0.4064)
			(end -1.1938 0.4064)
			(stroke
				(width 0.1)
				(type default)
			)
			(layer "F.Fab")
		)
		(fp_line
			(start -0.8636 -0.4064)
			(end -0.8636 -0.4572)
			(stroke
				(width 0.1)
				(type default)
			)
			(layer "F.Fab")
		)
		(fp_line
			(start -0.8636 -0.4572)
			(end 0.8636 -0.4572)
			(stroke
				(width 0.1)
				(type default)
			)
			(layer "F.Fab")
		)
		(fp_line
			(start -1.1938 0.4064)
			(end -1.1938 -0.4064)
			(stroke
				(width 0.1)
				(type default)
			)
			(layer "F.Fab")
		)
		(fp_line
			(start -1.1938 -0.4064)
			(end -0.8636 -0.4064)
			(stroke
				(width 0.1)
				(type default)
			)
			(layer "F.Fab")
		)
		(pad "1" smd rect
			(at -0.7366 0 90)
			(size 0.7112 0.8128)
			(layers "F.Cu" "F.Mask" "F.Paste")
			(net "PCEPLL4_VDDA18_PEX0_R")
		)
		(pad "2" smd rect
			(at 0.7366 0 90)
			(size 0.7112 0.8128)
			(layers "F.Cu" "F.Mask" "F.Paste")
			(net "GND")
		)
	)
	(footprint ""
		(layer "F.Cu")
		(at 326.154542 -124.159264 180)
		(property "Reference" "PC486"
			(at 0 0 180)
			(layer "F.SilkS")
			(hide yes)
			(effects
				(font
					(size 1.27 1.27)
				)
			)
		)
		(property "Value" ""
			(at 0 0 180)
			(layer "F.Fab")
			(effects
				(font
					(size 1.27 1.27)
				)
			)
		)
		(duplicate_pad_numbers_are_jumpers no)
		(fp_line
			(start 0.7874 0.4064)
			(end -0.7874 0.4064)
			(stroke
				(width 0.1524)
				(type default)
			)
			(layer "F.SilkS")
		)
		(fp_line
			(start 0.7874 -0.4064)
			(end 0.7874 0.4064)
			(stroke
				(width 0.1524)
				(type default)
			)
			(layer "F.SilkS")
		)
		(fp_line
			(start -0.7874 0.4064)
			(end -0.7874 -0.4064)
			(stroke
				(width 0.1524)
				(type default)
			)
			(layer "F.SilkS")
		)
		(fp_line
			(start -0.7874 -0.4064)
			(end 0.7874 -0.4064)
			(stroke
				(width 0.1524)
				(type default)
			)
			(layer "F.SilkS")
		)
		(fp_line
			(start 0.67945 0.3048)
			(end 0.120396 0.3048)
			(stroke
				(width 0.1)
				(type default)
			)
			(layer "F.Fab")
		)
		(fp_line
			(start 0.67945 -0.3048)
			(end 0.67945 0.3048)
			(stroke
				(width 0.1)
				(type default)
			)
			(layer "F.Fab")
		)
		(fp_line
			(start 0.12065 -0.2794)
			(end 0.12065 -0.3048)
			(stroke
				(width 0.1)
				(type default)
			)
			(layer "F.Fab")
		)
		(fp_line
			(start 0.12065 -0.3048)
			(end 0.67945 -0.3048)
			(stroke
				(width 0.1)
				(type default)
			)
			(layer "F.Fab")
		)
		(fp_line
			(start 0.120396 0.3048)
			(end 0.120396 0.2794)
			(stroke
				(width 0.1)
				(type default)
			)
			(layer "F.Fab")
		)
		(fp_line
			(start 0.120396 0.2794)
			(end -0.12065 0.2794)
			(stroke
				(width 0.1)
				(type default)
			)
			(layer "F.Fab")
		)
		(fp_line
			(start -0.12065 0.3048)
			(end -0.67945 0.3048)
			(stroke
				(width 0.1)
				(type default)
			)
			(layer "F.Fab")
		)
		(fp_line
			(start -0.12065 0.2794)
			(end -0.12065 0.3048)
			(stroke
				(width 0.1)
				(type default)
			)
			(layer "F.Fab")
		)
		(fp_line
			(start -0.12065 -0.2794)
			(end 0.12065 -0.2794)
			(stroke
				(width 0.1)
				(type default)
			)
			(layer "F.Fab")
		)
		(fp_line
			(start -0.12065 -0.305054)
			(end -0.12065 -0.2794)
			(stroke
				(width 0.1)
				(type default)
			)
			(layer "F.Fab")
		)
		(fp_line
			(start -0.67945 0.3048)
			(end -0.67945 -0.305054)
			(stroke
				(width 0.1)
				(type default)
			)
			(layer "F.Fab")
		)
		(fp_line
			(start -0.67945 -0.305054)
			(end -0.12065 -0.305054)
			(stroke
				(width 0.1)
				(type default)
			)
			(layer "F.Fab")
		)
		(pad "1" smd circle
			(at -0.40005 0 180)
			(size 0 0)
			(layers "F.Cu" "F.Mask" "F.Paste")
			(net "P3V3_AUX")
		)
		(pad "2" smd circle
			(at 0.40005 0 180)
			(size 0 0)
			(layers "F.Cu" "F.Mask" "F.Paste")
			(net "GND")
		)
	)
	(footprint ""
		(layer "F.Cu")
		(at 221.332806 -254.18542 -90)
		(property "Reference" "C4283"
			(at 0 0 270)
			(layer "F.SilkS")
			(hide yes)
			(effects
				(font
					(size 1.27 1.27)
				)
			)
		)
		(property "Value" ""
			(at 0 0 270)
			(layer "F.Fab")
			(effects
				(font
					(size 1.27 1.27)
				)
			)
		)
		(duplicate_pad_numbers_are_jumpers no)
		(fp_line
			(start -1.2954 0.5842)
			(end -1.2954 -0.5842)
			(stroke
				(width 0.1524)
				(type default)
			)
			(layer "F.SilkS")
		)
		(fp_line
			(start 1.2954 0.5842)
			(end -1.2954 0.5842)
			(stroke
				(width 0.1524)
				(type default)
			)
			(layer "F.SilkS")
		)
		(fp_line
			(start -1.2954 -0.5842)
			(end 1.2954 -0.5842)
			(stroke
				(width 0.1524)
				(type default)
			)
			(layer "F.SilkS")
		)
		(fp_line
			(start 1.2954 -0.5842)
			(end 1.2954 0.5842)
			(stroke
				(width 0.1524)
				(type default)
			)
			(layer "F.SilkS")
		)
		(fp_line
			(start -0.8636 0.4572)
			(end -0.8636 0.4064)
			(stroke
				(width 0.1)
				(type default)
			)
			(layer "F.Fab")
		)
		(fp_line
			(start 0.8636 0.4572)
			(end -0.8636 0.4572)
			(stroke
				(width 0.1)
				(type default)
			)
			(layer "F.Fab")
		)
		(fp_line
			(start -1.1938 0.4064)
			(end -1.1938 -0.4064)
			(stroke
				(width 0.1)
				(type default)
			)
			(layer "F.Fab")
		)
		(fp_line
			(start -0.8636 0.4064)
			(end -1.1938 0.4064)
			(stroke
				(width 0.1)
				(type default)
			)
			(layer "F.Fab")
		)
		(fp_line
			(start 0.8636 0.4064)
			(end 0.8636 0.4572)
			(stroke
				(width 0.1)
				(type default)
			)
			(layer "F.Fab")
		)
		(fp_line
			(start 1.1938 0.4064)
			(end 0.8636 0.4064)
			(stroke
				(width 0.1)
				(type default)
			)
			(layer "F.Fab")
		)
		(fp_line
			(start -1.1938 -0.4064)
			(end -0.8636 -0.4064)
			(stroke
				(width 0.1)
				(type default)
			)
			(layer "F.Fab")
		)
		(fp_line
			(start -0.8636 -0.4064)
			(end -0.8636 -0.4572)
			(stroke
				(width 0.1)
				(type default)
			)
			(layer "F.Fab")
		)
		(fp_line
			(start 0.8636 -0.4064)
			(end 1.1938 -0.4064)
			(stroke
				(width 0.1)
				(type default)
			)
			(layer "F.Fab")
		)
		(fp_line
			(start 1.1938 -0.4064)
			(end 1.1938 0.4064)
			(stroke
				(width 0.1)
				(type default)
			)
			(layer "F.Fab")
		)
		(fp_line
			(start -0.8636 -0.4572)
			(end 0.8636 -0.4572)
			(stroke
				(width 0.1)
				(type default)
			)
			(layer "F.Fab")
		)
		(fp_line
			(start 0.8636 -0.4572)
			(end 0.8636 -0.4064)
			(stroke
				(width 0.1)
				(type default)
			)
			(layer "F.Fab")
		)
		(pad "1" smd rect
			(at -0.7366 0 180)
			(size 0.7112 0.8128)
			(layers "F.Cu" "F.Mask" "F.Paste")
			(net "P1V25_SERDES_VDDPLL_PEX1_C1")
		)
		(pad "2" smd rect
			(at 0.7366 0 180)
			(size 0.7112 0.8128)
			(layers "F.Cu" "F.Mask" "F.Paste")
			(net "GND")
		)
	)
	(footprint ""
		(layer "F.Cu")
		(at 361.188 -179.07 180)
		(property "Reference" "R4705"
			(at 0 0 180)
			(layer "F.SilkS")
			(hide yes)
			(effects
				(font
					(size 1.27 1.27)
				)
			)
		)
		(property "Value" ""
			(at 0 0 180)
			(layer "F.Fab")
			(effects
				(font
					(size 1.27 1.27)
				)
			)
		)
		(duplicate_pad_numbers_are_jumpers no)
		(fp_line
			(start 0.7874 0.4064)
			(end -0.7874 0.4064)
			(stroke
				(width 0.1524)
				(type default)
			)
			(layer "F.SilkS")
		)
		(fp_line
			(start 0.7874 -0.4064)
			(end 0.7874 0.4064)
			(stroke
				(width 0.1524)
				(type default)
			)
			(layer "F.SilkS")
		)
		(fp_line
			(start -0.7874 0.4064)
			(end -0.7874 -0.4064)
			(stroke
				(width 0.1524)
				(type default)
			)
			(layer "F.SilkS")
		)
		(fp_line
			(start -0.7874 -0.4064)
			(end 0.7874 -0.4064)
			(stroke
				(width 0.1524)
				(type default)
			)
			(layer "F.SilkS")
		)
		(fp_line
			(start 0.67945 0.3048)
			(end 0.120396 0.3048)
			(stroke
				(width 0.1)
				(type default)
			)
			(layer "F.Fab")
		)
		(fp_line
			(start 0.67945 -0.3048)
			(end 0.67945 0.3048)
			(stroke
				(width 0.1)
				(type default)
			)
			(layer "F.Fab")
		)
		(fp_line
			(start 0.12065 -0.2794)
			(end 0.12065 -0.3048)
			(stroke
				(width 0.1)
				(type default)
			)
			(layer "F.Fab")
		)
		(fp_line
			(start 0.12065 -0.3048)
			(end 0.67945 -0.3048)
			(stroke
				(width 0.1)
				(type default)
			)
			(layer "F.Fab")
		)
		(fp_line
			(start 0.120396 0.3048)
			(end 0.120396 0.2794)
			(stroke
				(width 0.1)
				(type default)
			)
			(layer "F.Fab")
		)
		(fp_line
			(start 0.120396 0.2794)
			(end -0.12065 0.2794)
			(stroke
				(width 0.1)
				(type default)
			)
			(layer "F.Fab")
		)
		(fp_line
			(start -0.12065 0.3048)
			(end -0.67945 0.3048)
			(stroke
				(width 0.1)
				(type default)
			)
			(layer "F.Fab")
		)
		(fp_line
			(start -0.12065 0.2794)
			(end -0.12065 0.3048)
			(stroke
				(width 0.1)
				(type default)
			)
			(layer "F.Fab")
		)
		(fp_line
			(start -0.12065 -0.2794)
			(end 0.12065 -0.2794)
			(stroke
				(width 0.1)
				(type default)
			)
			(layer "F.Fab")
		)
		(fp_line
			(start -0.12065 -0.305054)
			(end -0.12065 -0.2794)
			(stroke
				(width 0.1)
				(type default)
			)
			(layer "F.Fab")
		)
		(fp_line
			(start -0.67945 0.3048)
			(end -0.67945 -0.305054)
			(stroke
				(width 0.1)
				(type default)
			)
			(layer "F.Fab")
		)
		(fp_line
			(start -0.67945 -0.305054)
			(end -0.12065 -0.305054)
			(stroke
				(width 0.1)
				(type default)
			)
			(layer "F.Fab")
		)
		(pad "1" smd circle
			(at -0.40005 0 180)
			(size 0 0)
			(layers "F.Cu" "F.Mask" "F.Paste")
			(net "PRSNT_SSD6_FPGA_PCA9555_N")
		)
		(pad "2" smd circle
			(at 0.40005 0 180)
			(size 0 0)
			(layers "F.Cu" "F.Mask" "F.Paste")
			(net "PRSNT_SSD6_FPGA_R_N")
		)
	)
)
